# S9S_MB_2U (Grand Teton) — schematic netlist excerpt (pin names and nets, part order shuffled) for the footprints in the layout excerpt that follows; sources: Cadence DE-HDL packaged netlist, KiCad conversion of 03242023_DA0F0TMBIJ0_F0T_Motherboard_J_brd_V01_OCP.brd

R1403  Q_RES  2K 1% CHIP  pkg 0402LF  page 219 : A = PWRGD_PCH_PWROK ; B = GND
PC329  Q_CAP  0.1UF 25V 10% EMPTY  pkg 0402  page 266 : A = PVCCIN_CPU0_CSPIN ; B = GND
C965  Q_CAP_DIFFBUS  DIFF BUS_0.22UF 6.3V 20% X6S  pkg C0201  page 173 : \1\ = P5E_CPU0_PE2_TX_C_DP<0> ; \2\ = P5E_CPU0_PE2_TX_DP<0>

(kicad_pcb
	(version 20260206)
	(generator "pcbnew")
	(generator_version "10.0")
	(general
		(thickness 1.6)
		(legacy_teardrops no)
	)
	(paper "A4")
	(title_block
		(title "03242023_DA0F0TMBIJ0_F0T_Motherboard_J_brd_V01_OCP.brd")
		(comment 1 "Grand Teton / footprints 2671-2673 of 6105")
	)
	(layers
		(0 "F.Cu" signal "TOP")
		(4 "In1.Cu" signal "GND")
		(6 "In2.Cu" signal "IN1")
		(8 "In3.Cu" signal "GND1")
		(10 "In4.Cu" signal "IN2")
		(12 "In5.Cu" signal "GND2")
		(14 "In6.Cu" signal "IN3")
		(16 "In7.Cu" signal "GND3")
		(18 "In8.Cu" signal "VCC")
		(20 "In9.Cu" signal "VCC1")
		(22 "In10.Cu" signal "GND4")
		(24 "In11.Cu" signal "IN4")
		(26 "In12.Cu" signal "GND5")
		(28 "In13.Cu" signal "IN5")
		(30 "In14.Cu" signal "GND6")
		(32 "In15.Cu" signal "IN6")
		(34 "In16.Cu" signal "GND7")
		(2 "B.Cu" signal "BOTTOM")
		(9 "F.Adhes" user "F.Adhesive")
		(11 "B.Adhes" user "B.Adhesive")
		(13 "F.Paste" user "Package Geometry/Pastemask Top")
		(15 "B.Paste" user "Package Geometry/Pastemask Bottom")
		(5 "F.SilkS" user "Ref Des/Silkscreen Top")
		(7 "B.SilkS" user "Ref Des/Silkscreen Bottom")
		(1 "F.Mask" user "Board Geometry/Soldermask Top")
		(3 "B.Mask" user "Board Geometry/Soldermask Bottom")
		(17 "Dwgs.User" user "User.Drawings")
		(19 "Cmts.User" user "User.Comments")
		(21 "Eco1.User" user "User.Eco1")
		(23 "Eco2.User" user "User.Eco2")
		(25 "Edge.Cuts" user "Board Geometry/Outline")
		(27 "Margin" user)
		(31 "F.CrtYd" user "Package Geometry/Place Bound Top")
		(29 "B.CrtYd" user "Package Geometry/Place Bound Bottom")
		(35 "F.Fab" user "Ref Des/Assembly Top")
		(33 "B.Fab" user "Ref Des/Assembly Bottom")
	)
	(footprint ""
		(layer "F.Cu")
		(at 362.646468 -359.94975)
		(property "Reference" "PC329"
			(at 0 0 0)
			(layer "F.SilkS")
			(hide yes)
			(effects
				(font
					(size 1.27 1.27)
				)
			)
		)
		(property "Value" ""
			(at 0 0 0)
			(layer "F.Fab")
			(effects
				(font
					(size 1.27 1.27)
				)
			)
		)
		(duplicate_pad_numbers_are_jumpers no)
		(fp_line
			(start -0.7874 -0.4064)
			(end 0.7874 -0.4064)
			(stroke
				(width 0.1524)
				(type default)
			)
			(layer "F.SilkS")
		)
		(fp_line
			(start -0.7874 0.4064)
			(end -0.7874 -0.4064)
			(stroke
				(width 0.1524)
				(type default)
			)
			(layer "F.SilkS")
		)
		(fp_line
			(start 0.7874 -0.4064)
			(end 0.7874 0.4064)
			(stroke
				(width 0.1524)
				(type default)
			)
			(layer "F.SilkS")
		)
		(fp_line
			(start 0.7874 0.4064)
			(end -0.7874 0.4064)
			(stroke
				(width 0.1524)
				(type default)
			)
			(layer "F.SilkS")
		)
		(fp_line
			(start -0.67945 -0.305054)
			(end -0.12065 -0.305054)
			(stroke
				(width 0.1)
				(type default)
			)
			(layer "F.Fab")
		)
		(fp_line
			(start -0.67945 0.3048)
			(end -0.67945 -0.305054)
			(stroke
				(width 0.1)
				(type default)
			)
			(layer "F.Fab")
		)
		(fp_line
			(start -0.12065 -0.305054)
			(end -0.12065 -0.2794)
			(stroke
				(width 0.1)
				(type default)
			)
			(layer "F.Fab")
		)
		(fp_line
			(start -0.12065 -0.2794)
			(end 0.12065 -0.2794)
			(stroke
				(width 0.1)
				(type default)
			)
			(layer "F.Fab")
		)
		(fp_line
			(start -0.12065 0.2794)
			(end -0.12065 0.3048)
			(stroke
				(width 0.1)
				(type default)
			)
			(layer "F.Fab")
		)
		(fp_line
			(start -0.12065 0.3048)
			(end -0.67945 0.3048)
			(stroke
				(width 0.1)
				(type default)
			)
			(layer "F.Fab")
		)
		(fp_line
			(start 0.120396 0.2794)
			(end -0.12065 0.2794)
			(stroke
				(width 0.1)
				(type default)
			)
			(layer "F.Fab")
		)
		(fp_line
			(start 0.120396 0.3048)
			(end 0.120396 0.2794)
			(stroke
				(width 0.1)
				(type default)
			)
			(layer "F.Fab")
		)
		(fp_line
			(start 0.12065 -0.3048)
			(end 0.67945 -0.3048)
			(stroke
				(width 0.1)
				(type default)
			)
			(layer "F.Fab")
		)
		(fp_line
			(start 0.12065 -0.2794)
			(end 0.12065 -0.3048)
			(stroke
				(width 0.1)
				(type default)
			)
			(layer "F.Fab")
		)
		(fp_line
			(start 0.67945 -0.3048)
			(end 0.67945 0.3048)
			(stroke
				(width 0.1)
				(type default)
			)
			(layer "F.Fab")
		)
		(fp_line
			(start 0.67945 0.3048)
			(end 0.120396 0.3048)
			(stroke
				(width 0.1)
				(type default)
			)
			(layer "F.Fab")
		)
		(pad "1" smd circle
			(at -0.40005 0)
			(size 0 0)
			(layers "F.Cu" "F.Mask" "F.Paste")
			(net "PVCCIN_CPU0_CSPIN")
		)
		(pad "2" smd circle
			(at 0.40005 0)
			(size 0 0)
			(layers "F.Cu" "F.Mask" "F.Paste")
			(net "GND")
		)
	)
	(footprint ""
		(layer "F.Cu")
		(at 417.34613 -402.371052 -90)
		(property "Reference" "C965"
			(at 0 0 270)
			(layer "F.SilkS")
			(hide yes)
			(effects
				(font
					(size 1.27 1.27)
				)
			)
		)
		(property "Value" ""
			(at 0 0 270)
			(layer "F.Fab")
			(effects
				(font
					(size 1.27 1.27)
				)
			)
		)
		(duplicate_pad_numbers_are_jumpers no)
		(fp_line
			(start -0.299974 0.150114)
			(end -0.299974 -0.150114)
			(stroke
				(width 0.1)
				(type default)
			)
			(layer "F.Fab")
		)
		(fp_line
			(start 0.299974 0.150114)
			(end -0.299974 0.150114)
			(stroke
				(width 0.1)
				(type default)
			)
			(layer "F.Fab")
		)
		(fp_line
			(start -0.299974 -0.150114)
			(end 0.299974 -0.150114)
			(stroke
				(width 0.1)
				(type default)
			)
			(layer "F.Fab")
		)
		(fp_line
			(start 0.299974 -0.150114)
			(end 0.299974 0.150114)
			(stroke
				(width 0.1)
				(type default)
			)
			(layer "F.Fab")
		)
		(pad "1" smd rect
			(at -0.2667 0 270)
			(size 0.3048 0.381)
			(layers "F.Cu" "F.Mask" "F.Paste")
			(net "P5E_CPU0_PE2_TX_C_DP<0>")
		)
		(pad "2" smd rect
			(at 0.2667 0 270)
			(size 0.3048 0.381)
			(layers "F.Cu" "F.Mask" "F.Paste")
			(net "P5E_CPU0_PE2_TX_DP<0>")
		)
	)
	(footprint ""
		(layer "F.Cu")
		(at 315.946028 -24.132032 180)
		(property "Reference" "R1403"
			(at 0 0 180)
			(layer "F.SilkS")
			(hide yes)
			(effects
				(font
					(size 1.27 1.27)
				)
			)
		)
		(property "Value" ""
			(at 0 0 180)
			(layer "F.Fab")
			(effects
				(font
					(size 1.27 1.27)
				)
			)
		)
		(duplicate_pad_numbers_are_jumpers no)
		(fp_line
			(start 0.7874 0.4064)
			(end -0.7874 0.4064)
			(stroke
				(width 0.1524)
				(type default)
			)
			(layer "F.SilkS")
		)
		(fp_line
			(start 0.7874 -0.4064)
			(end 0.7874 0.4064)
			(stroke
				(width 0.1524)
				(type default)
			)
			(layer "F.SilkS")
		)
		(fp_line
			(start -0.7874 0.4064)
			(end -0.7874 -0.4064)
			(stroke
				(width 0.1524)
				(type default)
			)
			(layer "F.SilkS")
		)
		(fp_line
			(start -0.7874 -0.4064)
			(end 0.7874 -0.4064)
			(stroke
				(width 0.1524)
				(type default)
			)
			(layer "F.SilkS")
		)
		(fp_line
			(start 0.67945 0.3048)
			(end 0.120396 0.3048)
			(stroke
				(width 0.1)
				(type default)
			)
			(layer "F.Fab")
		)
		(fp_line
			(start 0.67945 -0.3048)
			(end 0.67945 0.3048)
			(stroke
				(width 0.1)
				(type default)
			)
			(layer "F.Fab")
		)
		(fp_line
			(start 0.12065 -0.2794)
			(end 0.12065 -0.3048)
			(stroke
				(width 0.1)
				(type default)
			)
			(layer "F.Fab")
		)
		(fp_line
			(start 0.12065 -0.3048)
			(end 0.67945 -0.3048)
			(stroke
				(width 0.1)
				(type default)
			)
			(layer "F.Fab")
		)
		(fp_line
			(start 0.120396 0.3048)
			(end 0.120396 0.2794)
			(stroke
				(width 0.1)
				(type default)
			)
			(layer "F.Fab")
		)
		(fp_line
			(start 0.120396 0.2794)
			(end -0.12065 0.2794)
			(stroke
				(width 0.1)
				(type default)
			)
			(layer "F.Fab")
		)
		(fp_line
			(start -0.12065 0.3048)
			(end -0.67945 0.3048)
			(stroke
				(width 0.1)
				(type default)
			)
			(layer "F.Fab")
		)
		(fp_line
			(start -0.12065 0.2794)
			(end -0.12065 0.3048)
			(stroke
				(width 0.1)
				(type default)
			)
			(layer "F.Fab")
		)
		(fp_line
			(start -0.12065 -0.2794)
			(end 0.12065 -0.2794)
			(stroke
				(width 0.1)
				(type default)
			)
			(layer "F.Fab")
		)
		(fp_line
			(start -0.12065 -0.305054)
			(end -0.12065 -0.2794)
			(stroke
				(width 0.1)
				(type default)
			)
			(layer "F.Fab")
		)
		(fp_line
			(start -0.67945 0.3048)
			(end -0.67945 -0.305054)
			(stroke
				(width 0.1)
				(type default)
			)
			(layer "F.Fab")
		)
		(fp_line
			(start -0.67945 -0.305054)
			(end -0.12065 -0.305054)
			(stroke
				(width 0.1)
				(type default)
			)
			(layer "F.Fab")
		)
		(pad "1" smd circle
			(at -0.40005 0 180)
			(size 0 0)
			(layers "F.Cu" "F.Mask" "F.Paste")
			(net "PWRGD_PCH_PWROK")
		)
		(pad "2" smd circle
			(at 0.40005 0 180)
			(size 0 0)
			(layers "F.Cu" "F.Mask" "F.Paste")
			(net "GND")
		)
	)
)
